# S9S_MB_2U (Grand Teton) — schematic netlist excerpt (pin names and nets, part order shuffled) for the footprints in the layout excerpt that follows; sources: Cadence DE-HDL packaged netlist, KiCad conversion of 03242023_DA0F0TMBIJ0_F0T_Motherboard_J_brd_V01_OCP.brd

C1254  Q_CAP  10UF 6.3V 20% X6S  pkg C0603  page 189 : A = P1V05_PCH_PLL_AUX ; B = GND
R107  Q_RES  33.2 1% CHIP  pkg 0402LF  page 241 : A = SMB_HOST_3V3AUX_SCL_R ; B = SMB_HOST_CLK_BUF_3V3AUX_SCL

(kicad_pcb
	(version 20260206)
	(generator "pcbnew")
	(generator_version "10.0")
	(general
		(thickness 1.6)
		(legacy_teardrops no)
	)
	(paper "A4")
	(title_block
		(title "03242023_DA0F0TMBIJ0_F0T_Motherboard_J_brd_V01_OCP.brd")
		(comment 1 "Grand Teton / footprints 4423-4424 of 6105")
	)
	(layers
		(0 "F.Cu" signal "TOP")
		(4 "In1.Cu" signal "GND")
		(6 "In2.Cu" signal "IN1")
		(8 "In3.Cu" signal "GND1")
		(10 "In4.Cu" signal "IN2")
		(12 "In5.Cu" signal "GND2")
		(14 "In6.Cu" signal "IN3")
		(16 "In7.Cu" signal "GND3")
		(18 "In8.Cu" signal "VCC")
		(20 "In9.Cu" signal "VCC1")
		(22 "In10.Cu" signal "GND4")
		(24 "In11.Cu" signal "IN4")
		(26 "In12.Cu" signal "GND5")
		(28 "In13.Cu" signal "IN5")
		(30 "In14.Cu" signal "GND6")
		(32 "In15.Cu" signal "IN6")
		(34 "In16.Cu" signal "GND7")
		(2 "B.Cu" signal "BOTTOM")
		(9 "F.Adhes" user "F.Adhesive")
		(11 "B.Adhes" user "B.Adhesive")
		(13 "F.Paste" user "Package Geometry/Pastemask Top")
		(15 "B.Paste" user "Package Geometry/Pastemask Bottom")
		(5 "F.SilkS" user "Ref Des/Silkscreen Top")
		(7 "B.SilkS" user "Ref Des/Silkscreen Bottom")
		(1 "F.Mask" user "Board Geometry/Soldermask Top")
		(3 "B.Mask" user "Board Geometry/Soldermask Bottom")
		(17 "Dwgs.User" user "User.Drawings")
		(19 "Cmts.User" user "User.Comments")
		(21 "Eco1.User" user "User.Eco1")
		(23 "Eco2.User" user "User.Eco2")
		(25 "Edge.Cuts" user "Board Geometry/Outline")
		(27 "Margin" user)
		(31 "F.CrtYd" user "Package Geometry/Place Bound Top")
		(29 "B.CrtYd" user "Package Geometry/Place Bound Bottom")
		(35 "F.Fab" user "Ref Des/Assembly Top")
		(33 "B.Fab" user "Ref Des/Assembly Bottom")
	)
	(footprint ""
		(layer "B.Cu")
		(at 330.16698 -64.260984 45)
		(property "Reference" "C1254"
			(at 0 0 45)
			(layer "B.SilkS")
			(hide yes)
			(effects
				(font
					(size 1.27 1.27)
				)
				(justify mirror)
			)
		)
		(property "Value" ""
			(at 0 0 45)
			(layer "B.Fab")
			(effects
				(font
					(size 1.27 1.27)
				)
				(justify mirror)
			)
		)
		(duplicate_pad_numbers_are_jumpers no)
		(fp_line
			(start -1.295492 -0.584255)
			(end -1.295492 0.584255)
			(stroke
				(width 0.1524)
				(type default)
			)
			(layer "B.SilkS")
		)
		(fp_line
			(start -1.295492 0.584255)
			(end 1.295492 0.584255)
			(stroke
				(width 0.1524)
				(type default)
			)
			(layer "B.SilkS")
		)
		(fp_line
			(start 0 -0.584076)
			(end 0 0.584076)
			(stroke
				(width 0.1524)
				(type default)
			)
			(layer "B.SilkS")
		)
		(fp_line
			(start 1.295492 -0.584255)
			(end -1.295492 -0.584255)
			(stroke
				(width 0.1524)
				(type default)
			)
			(layer "B.SilkS")
		)
		(fp_line
			(start 1.295492 0.584255)
			(end 1.295492 -0.584255)
			(stroke
				(width 0.1524)
				(type default)
			)
			(layer "B.SilkS")
		)
		(fp_line
			(start -1.193835 -0.406446)
			(end -1.193835 0.406446)
			(stroke
				(width 0.1)
				(type default)
			)
			(layer "B.Fab")
		)
		(fp_line
			(start -0.863541 -0.457275)
			(end -0.863721 -0.406446)
			(stroke
				(width 0.1)
				(type default)
			)
			(layer "B.Fab")
		)
		(fp_line
			(start -0.863721 -0.406446)
			(end -1.193835 -0.406446)
			(stroke
				(width 0.1)
				(type default)
			)
			(layer "B.Fab")
		)
		(fp_line
			(start -1.193835 0.406446)
			(end -0.863721 0.406446)
			(stroke
				(width 0.1)
				(type default)
			)
			(layer "B.Fab")
		)
		(fp_line
			(start -0.863721 0.406446)
			(end -0.863541 0.457275)
			(stroke
				(width 0.1)
				(type default)
			)
			(layer "B.Fab")
		)
		(fp_line
			(start -0.863541 0.457275)
			(end 0.863541 0.457275)
			(stroke
				(width 0.1)
				(type default)
			)
			(layer "B.Fab")
		)
		(fp_line
			(start 0.863541 -0.457275)
			(end -0.863541 -0.457275)
			(stroke
				(width 0.1)
				(type default)
			)
			(layer "B.Fab")
		)
		(fp_line
			(start 0.863721 -0.406446)
			(end 0.863541 -0.457275)
			(stroke
				(width 0.1)
				(type default)
			)
			(layer "B.Fab")
		)
		(fp_line
			(start 1.193835 -0.406446)
			(end 0.863721 -0.406446)
			(stroke
				(width 0.1)
				(type default)
			)
			(layer "B.Fab")
		)
		(fp_line
			(start 0.863721 0.406446)
			(end 1.193835 0.406446)
			(stroke
				(width 0.1)
				(type default)
			)
			(layer "B.Fab")
		)
		(fp_line
			(start 0.863541 0.457275)
			(end 0.863721 0.406446)
			(stroke
				(width 0.1)
				(type default)
			)
			(layer "B.Fab")
		)
		(fp_line
			(start 1.193835 0.406446)
			(end 1.193835 -0.406446)
			(stroke
				(width 0.1)
				(type default)
			)
			(layer "B.Fab")
		)
		(pad "1" smd rect
			(at 0.7366 0 315)
			(size 0.7112 0.8128)
			(layers "B.Cu" "B.Mask" "B.Paste")
			(net "P1V05_PCH_PLL_AUX")
		)
		(pad "2" smd rect
			(at -0.7366 0 315)
			(size 0.7112 0.8128)
			(layers "B.Cu" "B.Mask" "B.Paste")
			(net "GND")
		)
	)
	(footprint ""
		(layer "B.Cu")
		(at 235.811822 -132.103114 90)
		(property "Reference" "R107"
			(at 0 0 90)
			(layer "B.SilkS")
			(hide yes)
			(effects
				(font
					(size 1.27 1.27)
				)
				(justify mirror)
			)
		)
		(property "Value" ""
			(at 0 0 90)
			(layer "B.Fab")
			(effects
				(font
					(size 1.27 1.27)
				)
				(justify mirror)
			)
		)
		(duplicate_pad_numbers_are_jumpers no)
		(fp_line
			(start 0.7874 -0.4064)
			(end -0.7874 -0.4064)
			(stroke
				(width 0.1524)
				(type default)
			)
			(layer "B.SilkS")
		)
		(fp_line
			(start -0.7874 -0.4064)
			(end -0.7874 0.4064)
			(stroke
				(width 0.1524)
				(type default)
			)
			(layer "B.SilkS")
		)
		(fp_line
			(start 0.7874 0.4064)
			(end 0.7874 -0.4064)
			(stroke
				(width 0.1524)
				(type default)
			)
			(layer "B.SilkS")
		)
		(fp_line
			(start -0.7874 0.4064)
			(end 0.7874 0.4064)
			(stroke
				(width 0.1524)
				(type default)
			)
			(layer "B.SilkS")
		)
		(fp_line
			(start 0.67945 -0.305054)
			(end 0.12065 -0.305054)
			(stroke
				(width 0.1)
				(type default)
			)
			(layer "B.Fab")
		)
		(fp_line
			(start 0.12065 -0.305054)
			(end 0.12065 -0.2794)
			(stroke
				(width 0.1)
				(type default)
			)
			(layer "B.Fab")
		)
		(fp_line
			(start -0.12065 -0.3048)
			(end -0.67945 -0.3048)
			(stroke
				(width 0.1)
				(type default)
			)
			(layer "B.Fab")
		)
		(fp_line
			(start -0.67945 -0.3048)
			(end -0.67945 0.3048)
			(stroke
				(width 0.1)
				(type default)
			)
			(layer "B.Fab")
		)
		(fp_line
			(start 0.12065 -0.2794)
			(end -0.12065 -0.2794)
			(stroke
				(width 0.1)
				(type default)
			)
			(layer "B.Fab")
		)
		(fp_line
			(start -0.12065 -0.2794)
			(end -0.12065 -0.3048)
			(stroke
				(width 0.1)
				(type default)
			)
			(layer "B.Fab")
		)
		(fp_line
			(start 0.12065 0.2794)
			(end 0.12065 0.3048)
			(stroke
				(width 0.1)
				(type default)
			)
			(layer "B.Fab")
		)
		(fp_line
			(start -0.120396 0.2794)
			(end 0.12065 0.2794)
			(stroke
				(width 0.1)
				(type default)
			)
			(layer "B.Fab")
		)
		(fp_line
			(start 0.67945 0.3048)
			(end 0.67945 -0.305054)
			(stroke
				(width 0.1)
				(type default)
			)
			(layer "B.Fab")
		)
		(fp_line
			(start 0.12065 0.3048)
			(end 0.67945 0.3048)
			(stroke
				(width 0.1)
				(type default)
			)
			(layer "B.Fab")
		)
		(fp_line
			(start -0.120396 0.3048)
			(end -0.120396 0.2794)
			(stroke
				(width 0.1)
				(type default)
			)
			(layer "B.Fab")
		)
		(fp_line
			(start -0.67945 0.3048)
			(end -0.120396 0.3048)
			(stroke
				(width 0.1)
				(type default)
			)
			(layer "B.Fab")
		)
		(pad "1" smd circle
			(at 0.40005 0 270)
			(size 0 0)
			(layers "B.Cu" "B.Mask" "B.Paste")
			(net "SMB_HOST_3V3AUX_SCL_R")
		)
		(pad "2" smd circle
			(at -0.40005 0 270)
			(size 0 0)
			(layers "B.Cu" "B.Mask" "B.Paste")
			(net "SMB_HOST_CLK_BUF_3V3AUX_SCL")
		)
	)
)
